(kicad_pcb
	(version 20260206)
	(generator "pcbnew")
	(generator_version "10.0")
	(general
		(thickness 1.6)
		(legacy_teardrops no)
	)
	(paper "A4")
	(title_block
		(title "peb — Lightning_PEB_BRD.brd")
		(comment 1 "Lightning (Wiwynn / Facebook NVMe JBOF) / footprints 38-40 of 2563")
	)
	(layers
		(0 "F.Cu" signal "TOP")
		(4 "In1.Cu" signal "L2GND")
		(6 "In2.Cu" signal "L3")
		(8 "In3.Cu" signal "L4VCC")
		(10 "In4.Cu" signal "L5VCC")
		(12 "In5.Cu" signal "L6")
		(14 "In6.Cu" signal "L7GND")
		(2 "B.Cu" signal "BOTTOM")
		(9 "F.Adhes" user "F.Adhesive")
		(11 "B.Adhes" user "B.Adhesive")
		(13 "F.Paste" user "Package Geometry/Pastemask Top")
		(15 "B.Paste" user "Package Geometry/Pastemask Bottom")
		(5 "F.SilkS" user "Ref Des/Silkscreen Top")
		(7 "B.SilkS" user "Ref Des/Silkscreen Bottom")
		(1 "F.Mask" user "Board Geometry/Soldermask Top")
		(3 "B.Mask" user "Board Geometry/Soldermask Bottom")
		(17 "Dwgs.User" user "User.Drawings")
		(19 "Cmts.User" user "User.Comments")
		(21 "Eco1.User" user "User.Eco1")
		(23 "Eco2.User" user "User.Eco2")
		(25 "Edge.Cuts" user "Board Geometry/Outline")
		(27 "Margin" user)
		(31 "F.CrtYd" user "Package Geometry/Place Bound Top")
		(29 "B.CrtYd" user "Package Geometry/Place Bound Bottom")
		(35 "F.Fab" user "Ref Des/Assembly Top")
		(33 "B.Fab" user "Ref Des/Assembly Bottom")
	)
	(footprint ""
		(layer "F.Cu")
		(at 222.758 -4.699 -90)
		(property "Reference" "Q19"
			(at 0 0 270)
			(layer "F.SilkS")
			(hide yes)
			(effects
				(font
					(size 1.27 1.27)
				)
			)
		)
		(property "Value" "2N7002K-1-GP"
			(at 0.127 -8.9662 270)
			(unlocked yes)
			(layer "F.Fab")
			(hide yes)
			(effects
				(font
					(size 1.016 1.016)
					(thickness 0.1524)
				)
			)
		)
		(property "Device Type" "SOT23DGS2D4H44"
			(at 0.127 -10.4902 270)
			(unlocked yes)
			(layer "F.Fab")
			(hide yes)
			(effects
				(font
					(size 1.016 1.016)
					(thickness 0.1524)
				)
			)
		)
		(duplicate_pad_numbers_are_jumpers no)
		(fp_line
			(start -1.651 1.778)
			(end 1.651 1.778)
			(stroke
				(width 0.1524)
				(type default)
			)
			(layer "F.SilkS")
		)
		(fp_line
			(start 1.651 1.778)
			(end 1.651 -1.778)
			(stroke
				(width 0.1524)
				(type default)
			)
			(layer "F.SilkS")
		)
		(fp_line
			(start -1.651 -1.778)
			(end -1.651 1.778)
			(stroke
				(width 0.1524)
				(type default)
			)
			(layer "F.SilkS")
		)
		(fp_line
			(start 1.651 -1.778)
			(end -1.651 -1.778)
			(stroke
				(width 0.1524)
				(type default)
			)
			(layer "F.SilkS")
		)
		(fp_poly
			(pts
				(xy -1.778 1.8796) (xy -1.778 -1.8796) (xy 1.778 -1.8796) (xy 1.778 1.8796)
			)
			(stroke
				(width 0)
				(type default)
			)
			(fill no)
			(layer "F.CrtYd")
		)
		(fp_poly
			(pts
				(xy -1.778 1.8796) (xy -1.778 -1.8796) (xy 1.778 -1.8796) (xy 1.778 1.8796)
			)
			(stroke
				(width 0)
				(type default)
			)
			(fill no)
			(layer "F.Fab")
		)
		(pad "D" smd custom
			(at 0 -0.9525 270)
			(size 0.1905 0.1905)
			(layers "F.Cu" "F.Mask" "F.Paste")
			(net "DEBUG_CONSOLE_LED_0")
			(options
				(clearance outline)
				(anchor circle)
			)
			(primitives
				(gr_poly
					(pts
						(arc
							(start -0.1778 0.5715)
							(mid -0.321484 0.511984)
							(end -0.381 0.3683)
						)
						(arc
							(start -0.381 -0.3683)
							(mid -0.321484 -0.511984)
							(end -0.1778 -0.5715)
						)
						(arc
							(start 0.1778 -0.5715)
							(mid 0.321484 -0.511984)
							(end 0.381 -0.3683)
						)
						(arc
							(start 0.381 0.3683)
							(mid 0.321484 0.511984)
							(end 0.1778 0.5715)
						)
					)
					(width 0)
					(fill yes)
				)
			)
		)
		(pad "G" smd custom
			(at -0.98425 0.9525 270)
			(size 0.1905 0.1905)
			(layers "F.Cu" "F.Mask" "F.Paste")
			(net "BMC_CONSOLE_LED0_R")
			(options
				(clearance outline)
				(anchor circle)
			)
			(primitives
				(gr_poly
					(pts
						(arc
							(start -0.1778 0.5715)
							(mid -0.321484 0.511984)
							(end -0.381 0.3683)
						)
						(arc
							(start -0.381 -0.3683)
							(mid -0.321484 -0.511984)
							(end -0.1778 -0.5715)
						)
						(arc
							(start 0.1778 -0.5715)
							(mid 0.321484 -0.511984)
							(end 0.381 -0.3683)
						)
						(arc
							(start 0.381 0.3683)
							(mid 0.321484 0.511984)
							(end 0.1778 0.5715)
						)
					)
					(width 0)
					(fill yes)
				)
			)
		)
		(pad "S" smd custom
			(at 0.98425 0.9525 270)
			(size 0.1905 0.1905)
			(layers "F.Cu" "F.Mask" "F.Paste")
			(net "GND")
			(options
				(clearance outline)
				(anchor circle)
			)
			(primitives
				(gr_poly
					(pts
						(arc
							(start -0.1778 0.5715)
							(mid -0.321484 0.511984)
							(end -0.381 0.3683)
						)
						(arc
							(start -0.381 -0.3683)
							(mid -0.321484 -0.511984)
							(end -0.1778 -0.5715)
						)
						(arc
							(start 0.1778 -0.5715)
							(mid 0.321484 -0.511984)
							(end 0.381 -0.3683)
						)
						(arc
							(start 0.381 0.3683)
							(mid 0.321484 0.511984)
							(end 0.1778 0.5715)
						)
					)
					(width 0)
					(fill yes)
				)
			)
		)
	)
	(footprint ""
		(layer "F.Cu")
		(at 138.4173 -33.54324)
		(property "Reference" "C386"
			(at 0 0 0)
			(layer "F.SilkS")
			(hide yes)
			(effects
				(font
					(size 1.27 1.27)
				)
			)
		)
		(property "Value" "SCD22U10V2KX-1GP"
			(at 1.1811 -2.7051 0)
			(unlocked yes)
			(layer "F.Fab")
			(hide yes)
			(effects
				(font
					(size 1.016 1.016)
					(thickness 0.1524)
				)
			)
		)
		(property "Device Type" "C402H22"
			(at 1.1811 -4.2291 0)
			(unlocked yes)
			(layer "F.Fab")
			(hide yes)
			(effects
				(font
					(size 1.016 1.016)
					(thickness 0.1524)
				)
			)
		)
		(duplicate_pad_numbers_are_jumpers no)
		(fp_rect
			(start -0.4318 0.9525)
			(end 0.4318 -0.9525)
			(stroke
				(width 0)
				(type default)
			)
			(fill no)
			(layer "F.CrtYd")
		)
		(fp_rect
			(start -0.4318 0.9525)
			(end 0.4318 -0.9525)
			(stroke
				(width 0)
				(type default)
			)
			(fill no)
			(layer "F.Fab")
		)
		(pad "1" smd custom
			(at 0 -0.4445)
			(size 0.1524 0.1524)
			(layers "F.Cu" "F.Mask" "F.Paste")
			(net "PCIE_TX_CAP_N83")
			(options
				(clearance outline)
				(anchor circle)
			)
			(primitives
				(gr_poly
					(pts
						(arc
							(start 0.3048 -0.2032)
							(mid 0.275042 -0.275042)
							(end 0.2032 -0.3048)
						)
						(arc
							(start -0.2032 -0.3048)
							(mid -0.275042 -0.275042)
							(end -0.3048 -0.2032)
						)
						(arc
							(start -0.3048 0.2032)
							(mid -0.275042 0.275042)
							(end -0.2032 0.3048)
						)
						(arc
							(start 0.2032 0.3048)
							(mid 0.275042 0.275042)
							(end 0.3048 0.2032)
						)
					)
					(width 0)
					(fill yes)
				)
			)
		)
		(pad "2" smd custom
			(at 0 0.4445)
			(size 0.1524 0.1524)
			(layers "F.Cu" "F.Mask" "F.Paste")
			(net "PCIE_TX_N83")
			(options
				(clearance outline)
				(anchor circle)
			)
			(primitives
				(gr_poly
					(pts
						(arc
							(start 0.3048 -0.2032)
							(mid 0.275042 -0.275042)
							(end 0.2032 -0.3048)
						)
						(arc
							(start -0.2032 -0.3048)
							(mid -0.275042 -0.275042)
							(end -0.3048 -0.2032)
						)
						(arc
							(start -0.3048 0.2032)
							(mid -0.275042 0.275042)
							(end -0.2032 0.3048)
						)
						(arc
							(start 0.2032 0.3048)
							(mid 0.275042 0.275042)
							(end 0.3048 0.2032)
						)
					)
					(width 0)
					(fill yes)
				)
			)
		)
	)
	(footprint ""
		(layer "F.Cu")
		(at 48.133 -145.415 180)
		(property "Reference" "R229"
			(at 0 0 180)
			(layer "F.SilkS")
			(hide yes)
			(effects
				(font
					(size 1.27 1.27)
				)
			)
		)
		(property "Value" "4K7R2F-GP"
			(at 0.064008 -3.993896 180)
			(unlocked yes)
			(layer "F.Fab")
			(hide yes)
			(effects
				(font
					(size 1.016 1.016)
					(thickness 0.1524)
				)
			)
		)
		(property "Device Type" "R402H16"
			(at 0.064008 -5.517896 180)
			(unlocked yes)
			(layer "F.Fab")
			(hide yes)
			(effects
				(font
					(size 1.016 1.016)
					(thickness 0.1524)
				)
			)
		)
		(duplicate_pad_numbers_are_jumpers no)
		(fp_line
			(start 0.508 -0.9398)
			(end -0.508 -0.9398)
			(stroke
				(width 0.1524)
				(type default)
			)
			(layer "F.SilkS")
		)
		(fp_line
			(start -0.508 -0.9398)
			(end -0.508 0.9398)
			(stroke
				(width 0.1524)
				(type default)
			)
			(layer "F.SilkS")
		)
		(fp_rect
			(start -0.508 0.9398)
			(end 0.508 -0.9398)
			(stroke
				(width 0)
				(type default)
			)
			(fill no)
			(layer "F.CrtYd")
		)
		(fp_rect
			(start -0.508 0.9398)
			(end 0.508 -0.9398)
			(stroke
				(width 0)
				(type default)
			)
			(fill no)
			(layer "F.Fab")
		)
		(pad "1" smd custom
			(at 0 -0.4445 180)
			(size 0.1397 0.1397)
			(layers "F.Cu" "F.Mask" "F.Paste")
			(net "HB_OUT_BMC")
			(options
				(clearance outline)
				(anchor circle)
			)
			(primitives
				(gr_poly
					(pts
						(arc
							(start -0.1778 -0.2794)
							(mid -0.249642 -0.249642)
							(end -0.2794 -0.1778)
						)
						(arc
							(start -0.2794 0.1778)
							(mid -0.249642 0.249642)
							(end -0.1778 0.2794)
						)
						(arc
							(start 0.1778 0.2794)
							(mid 0.249642 0.249642)
							(end 0.2794 0.1778)
						)
						(arc
							(start 0.2794 -0.1778)
							(mid 0.249642 -0.249642)
							(end 0.1778 -0.2794)
						)
					)
					(width 0)
					(fill yes)
				)
			)
		)
		(pad "2" smd custom
			(at 0 0.4445 180)
			(size 0.1397 0.1397)
			(layers "F.Cu" "F.Mask" "F.Paste")
			(net "P3V3_STBY")
			(options
				(clearance outline)
				(anchor circle)
			)
			(primitives
				(gr_poly
					(pts
						(arc
							(start -0.1778 -0.2794)
							(mid -0.249642 -0.249642)
							(end -0.2794 -0.1778)
						)
						(arc
							(start -0.2794 0.1778)
							(mid -0.249642 0.249642)
							(end -0.1778 0.2794)
						)
						(arc
							(start 0.1778 0.2794)
							(mid 0.249642 0.249642)
							(end 0.2794 0.1778)
						)
						(arc
							(start 0.2794 -0.1778)
							(mid 0.249642 -0.249642)
							(end 0.1778 -0.2794)
						)
					)
					(width 0)
					(fill yes)
				)
			)
		)
	)
)
